# BASEBOARD_FAB2 (Tioga Pass) — schematic netlist excerpt (pin names and nets, part order shuffled) for the footprints in the layout excerpt that follows; sources: Cadence DE-HDL packaged netlist, KiCad conversion of Wiwynn_Tioga_Pass_MB.brd

C5G21  CAP  47UF 4V 20% X6S  pkg 0805  page 242 : A = PVDDQ_ABC ; B = GND
R7E18  RES  4.75K 1% CHIP  pkg 0402  page 192 : A = P3V3_STBY ; B = RST_RSMRST_N
R8E21  RES  0.0 5% CHIP  pkg 0402  page 142 : A = FM_PE_SPRV_WAKE_N ; B = FM_ALL_WAKE_N

(kicad_pcb
	(version 20260206)
	(generator "pcbnew")
	(generator_version "10.0")
	(general
		(thickness 1.6)
		(legacy_teardrops no)
	)
	(paper "A4")
	(title_block
		(title "Wiwynn_Tioga_Pass_MB.brd")
		(comment 1 "Tioga Pass / footprints 2485-2487 of 4770")
	)
	(layers
		(0 "F.Cu" signal "TOP")
		(4 "In1.Cu" signal "L2GND")
		(6 "In2.Cu" signal "L3")
		(8 "In3.Cu" signal "L4GND")
		(10 "In4.Cu" signal "L5")
		(12 "In5.Cu" signal "L6GND")
		(14 "In6.Cu" signal "L7VCC")
		(16 "In7.Cu" signal "L8VCC")
		(18 "In8.Cu" signal "L9GND")
		(20 "In9.Cu" signal "L10")
		(22 "In10.Cu" signal "L11GND")
		(24 "In11.Cu" signal "L12")
		(26 "In12.Cu" signal "L13GND")
		(2 "B.Cu" signal "BOTTOM")
		(9 "F.Adhes" user "F.Adhesive")
		(11 "B.Adhes" user "B.Adhesive")
		(13 "F.Paste" user "Package Geometry/Pastemask Top")
		(15 "B.Paste" user "Package Geometry/Pastemask Bottom")
		(5 "F.SilkS" user "Ref Des/Silkscreen Top")
		(7 "B.SilkS" user "Ref Des/Silkscreen Bottom")
		(1 "F.Mask" user "Board Geometry/Soldermask Top")
		(3 "B.Mask" user "Board Geometry/Soldermask Bottom")
		(17 "Dwgs.User" user "User.Drawings")
		(19 "Cmts.User" user "User.Comments")
		(21 "Eco1.User" user "User.Eco1")
		(23 "Eco2.User" user "User.Eco2")
		(25 "Edge.Cuts" user "Board Geometry/Outline")
		(27 "Margin" user)
		(31 "F.CrtYd" user "Package Geometry/Place Bound Top")
		(29 "B.CrtYd" user "Package Geometry/Place Bound Bottom")
		(35 "F.Fab" user "Ref Des/Assembly Top")
		(33 "B.Fab" user "Ref Des/Assembly Bottom")
	)
	(footprint ""
		(layer "B.Cu")
		(at 379.3363 -67.21856)
		(property "Reference" "R7E18"
			(at 0 0 0)
			(layer "B.SilkS")
			(hide yes)
			(effects
				(font
					(size 1.27 1.27)
				)
				(justify mirror)
			)
		)
		(property "Value" ""
			(at 0 0 0)
			(layer "B.Fab")
			(effects
				(font
					(size 1.27 1.27)
				)
				(justify mirror)
			)
		)
		(duplicate_pad_numbers_are_jumpers no)
		(fp_poly
			(pts
				(xy 0.2794 -0.1016) (xy -0.2794 -0.1016) (xy -0.2794 0.9906) (xy 0.2794 0.9906)
			)
			(stroke
				(width 0)
				(type default)
			)
			(fill no)
			(layer "B.CrtYd")
		)
		(fp_line
			(start -0.2794 -0.1016)
			(end 0.2794 -0.1016)
			(stroke
				(width 0.1)
				(type default)
			)
			(layer "B.Fab")
		)
		(fp_line
			(start -0.2794 0.9906)
			(end -0.2794 -0.1016)
			(stroke
				(width 0.1)
				(type default)
			)
			(layer "B.Fab")
		)
		(fp_line
			(start 0.2794 -0.1016)
			(end 0.2794 0.9906)
			(stroke
				(width 0.1)
				(type default)
			)
			(layer "B.Fab")
		)
		(fp_line
			(start 0.2794 0.9906)
			(end -0.2794 0.9906)
			(stroke
				(width 0.1)
				(type default)
			)
			(layer "B.Fab")
		)
		(pad "1" smd rect
			(at 0 0 180)
			(size 0.508 0.508)
			(layers "B.Cu" "B.Mask" "B.Paste")
			(net "P3V3_STBY")
		)
		(pad "2" smd rect
			(at 0 0.889 180)
			(size 0.508 0.508)
			(layers "B.Cu" "B.Mask" "B.Paste")
			(net "RST_RSMRST_N")
		)
		(zone
			(layer "B.Cu")
			(hatch none 0.5)
			(connect_pads
				(clearance 0)
			)
			(min_thickness 0.25)
			(keepout
				(tracks allowed)
				(vias not_allowed)
				(pads allowed)
				(copperpour not_allowed)
				(footprints allowed)
			)
			(placement
				(enabled no)
				(sheetname "")
			)
			(fill
				(thermal_gap 0.5)
				(thermal_bridge_width 0.5)
				(island_removal_mode 0)
			)
			(polygon
				(pts
					(xy 379.5903 -66.96456) (xy 379.0823 -66.96456) (xy 379.0823 -66.58356) (xy 379.5903 -66.58356)
				)
			)
		)
		(zone
			(layer "B.Cu")
			(hatch none 0.5)
			(connect_pads
				(clearance 0)
			)
			(min_thickness 0.25)
			(keepout
				(tracks not_allowed)
				(vias allowed)
				(pads allowed)
				(copperpour not_allowed)
				(footprints allowed)
			)
			(placement
				(enabled no)
				(sheetname "")
			)
			(fill
				(thermal_gap 0.5)
				(thermal_bridge_width 0.5)
				(island_removal_mode 0)
			)
			(polygon
				(pts
					(xy 379.5903 -66.58356) (xy 379.0823 -66.58356) (xy 379.0823 -66.96456) (xy 379.5903 -66.96456)
				)
			)
		)
	)
	(footprint ""
		(layer "B.Cu")
		(at 259.6896 -3.321812 90)
		(property "Reference" "C5G21"
			(at -1.64973 0.78994 180)
			(unlocked yes)
			(layer "B.SilkS")
			(effects
				(font
					(size 0.7874 0.5842)
					(thickness 0.1524)
				)
				(justify mirror)
			)
		)
		(property "Value" ""
			(at 0 0 90)
			(layer "B.Fab")
			(effects
				(font
					(size 1.27 1.27)
				)
				(justify mirror)
			)
		)
		(duplicate_pad_numbers_are_jumpers no)
		(fp_rect
			(start -0.7239 -0.2159)
			(end 0.7239 1.9939)
			(stroke
				(width 0)
				(type default)
			)
			(fill no)
			(layer "B.CrtYd")
		)
		(fp_line
			(start 0.7239 -0.2159)
			(end 0.7239 1.9939)
			(stroke
				(width 0.1)
				(type default)
			)
			(layer "B.Fab")
		)
		(fp_line
			(start -0.7239 -0.2159)
			(end 0.7239 -0.2159)
			(stroke
				(width 0.1)
				(type default)
			)
			(layer "B.Fab")
		)
		(fp_line
			(start 0.7239 1.9939)
			(end -0.7239 1.9939)
			(stroke
				(width 0.1)
				(type default)
			)
			(layer "B.Fab")
		)
		(fp_line
			(start -0.7239 1.9939)
			(end -0.7239 -0.2159)
			(stroke
				(width 0.1)
				(type default)
			)
			(layer "B.Fab")
		)
		(pad "1" smd rect
			(at 0 0 270)
			(size 1.27 1.016)
			(layers "B.Cu" "B.Mask" "B.Paste")
			(net "PVDDQ_ABC")
		)
		(pad "2" smd rect
			(at 0 1.778 270)
			(size 1.27 1.016)
			(layers "B.Cu" "B.Mask" "B.Paste")
			(net "GND")
		)
		(zone
			(layer "B.Cu")
			(hatch none 0.5)
			(connect_pads
				(clearance 0)
			)
			(min_thickness 0.25)
			(keepout
				(tracks not_allowed)
				(vias allowed)
				(pads allowed)
				(copperpour not_allowed)
				(footprints allowed)
			)
			(placement
				(enabled no)
				(sheetname "")
			)
			(fill
				(thermal_gap 0.5)
				(thermal_bridge_width 0.5)
				(island_removal_mode 0)
			)
			(polygon
				(pts
					(xy 260.1976 -2.686812) (xy 260.9596 -2.686812) (xy 260.9596 -3.956812) (xy 260.1976 -3.956812)
				)
			)
		)
	)
	(footprint ""
		(layer "B.Cu")
		(at 479.923602 -58.010298 90)
		(property "Reference" "R8E21"
			(at 0 0 90)
			(layer "B.SilkS")
			(hide yes)
			(effects
				(font
					(size 1.27 1.27)
				)
				(justify mirror)
			)
		)
		(property "Value" ""
			(at 0 0 90)
			(layer "B.Fab")
			(effects
				(font
					(size 1.27 1.27)
				)
				(justify mirror)
			)
		)
		(duplicate_pad_numbers_are_jumpers no)
		(fp_poly
			(pts
				(xy 0.2794 -0.1016) (xy -0.2794 -0.1016) (xy -0.2794 0.9906) (xy 0.2794 0.9906)
			)
			(stroke
				(width 0)
				(type default)
			)
			(fill no)
			(layer "B.CrtYd")
		)
		(fp_line
			(start 0.2794 -0.1016)
			(end 0.2794 0.9906)
			(stroke
				(width 0.1)
				(type default)
			)
			(layer "B.Fab")
		)
		(fp_line
			(start -0.2794 -0.1016)
			(end 0.2794 -0.1016)
			(stroke
				(width 0.1)
				(type default)
			)
			(layer "B.Fab")
		)
		(fp_line
			(start 0.2794 0.9906)
			(end -0.2794 0.9906)
			(stroke
				(width 0.1)
				(type default)
			)
			(layer "B.Fab")
		)
		(fp_line
			(start -0.2794 0.9906)
			(end -0.2794 -0.1016)
			(stroke
				(width 0.1)
				(type default)
			)
			(layer "B.Fab")
		)
		(pad "1" smd rect
			(at 0 0 270)
			(size 0.508 0.508)
			(layers "B.Cu" "B.Mask" "B.Paste")
			(net "FM_PE_SPRV_WAKE_N")
		)
		(pad "2" smd rect
			(at 0 0.889 270)
			(size 0.508 0.508)
			(layers "B.Cu" "B.Mask" "B.Paste")
			(net "FM_ALL_WAKE_N")
		)
		(zone
			(layer "B.Cu")
			(hatch none 0.5)
			(connect_pads
				(clearance 0)
			)
			(min_thickness 0.25)
			(keepout
				(tracks allowed)
				(vias not_allowed)
				(pads allowed)
				(copperpour not_allowed)
				(footprints allowed)
			)
			(placement
				(enabled no)
				(sheetname "")
			)
			(fill
				(thermal_gap 0.5)
				(thermal_bridge_width 0.5)
				(island_removal_mode 0)
			)
			(polygon
				(pts
					(xy 480.177602 -58.264298) (xy 480.177602 -57.756298) (xy 480.558602 -57.756298) (xy 480.558602 -58.264298)
				)
			)
		)
		(zone
			(layer "B.Cu")
			(hatch none 0.5)
			(connect_pads
				(clearance 0)
			)
			(min_thickness 0.25)
			(keepout
				(tracks not_allowed)
				(vias allowed)
				(pads allowed)
				(copperpour not_allowed)
				(footprints allowed)
			)
			(placement
				(enabled no)
				(sheetname "")
			)
			(fill
				(thermal_gap 0.5)
				(thermal_bridge_width 0.5)
				(island_removal_mode 0)
			)
			(polygon
				(pts
					(xy 480.558602 -58.264298) (xy 480.558602 -57.756298) (xy 480.177602 -57.756298) (xy 480.177602 -58.264298)
				)
			)
		)
	)
)
